# S9S_MB_2U (Grand Teton) — schematic netlist excerpt (pin names and nets, part order shuffled) for the footprints in the layout excerpt that follows; sources: Cadence DE-HDL packaged netlist, KiCad conversion of 03242023_DA0F0TMBIJ0_F0T_Motherboard_J_brd_V01_OCP.brd

R777  Q_RES  10 1% CHIP  pkg 0402LF  page 131 : A = JTAG_DBP_PREQ_N_R ; B = JTAG_DBP_PREQ_N
C2017  Q_CAP  0.1UF 25V 10% X7R  pkg 0402  page 172 : A = P3V3_OCP_V3_2_R ; B = GND

(kicad_pcb
	(version 20260206)
	(generator "pcbnew")
	(generator_version "10.0")
	(general
		(thickness 1.6)
		(legacy_teardrops no)
	)
	(paper "A4")
	(title_block
		(title "03242023_DA0F0TMBIJ0_F0T_Motherboard_J_brd_V01_OCP.brd")
		(comment 1 "Grand Teton / footprints 1924-1925 of 6105")
	)
	(layers
		(0 "F.Cu" signal "TOP")
		(4 "In1.Cu" signal "GND")
		(6 "In2.Cu" signal "IN1")
		(8 "In3.Cu" signal "GND1")
		(10 "In4.Cu" signal "IN2")
		(12 "In5.Cu" signal "GND2")
		(14 "In6.Cu" signal "IN3")
		(16 "In7.Cu" signal "GND3")
		(18 "In8.Cu" signal "VCC")
		(20 "In9.Cu" signal "VCC1")
		(22 "In10.Cu" signal "GND4")
		(24 "In11.Cu" signal "IN4")
		(26 "In12.Cu" signal "GND5")
		(28 "In13.Cu" signal "IN5")
		(30 "In14.Cu" signal "GND6")
		(32 "In15.Cu" signal "IN6")
		(34 "In16.Cu" signal "GND7")
		(2 "B.Cu" signal "BOTTOM")
		(9 "F.Adhes" user "F.Adhesive")
		(11 "B.Adhes" user "B.Adhesive")
		(13 "F.Paste" user "Package Geometry/Pastemask Top")
		(15 "B.Paste" user "Package Geometry/Pastemask Bottom")
		(5 "F.SilkS" user "Ref Des/Silkscreen Top")
		(7 "B.SilkS" user "Ref Des/Silkscreen Bottom")
		(1 "F.Mask" user "Board Geometry/Soldermask Top")
		(3 "B.Mask" user "Board Geometry/Soldermask Bottom")
		(17 "Dwgs.User" user "User.Drawings")
		(19 "Cmts.User" user "User.Comments")
		(21 "Eco1.User" user "User.Eco1")
		(23 "Eco2.User" user "User.Eco2")
		(25 "Edge.Cuts" user "Board Geometry/Outline")
		(27 "Margin" user)
		(31 "F.CrtYd" user "Package Geometry/Place Bound Top")
		(29 "B.CrtYd" user "Package Geometry/Place Bound Bottom")
		(35 "F.Fab" user "Ref Des/Assembly Top")
		(33 "B.Fab" user "Ref Des/Assembly Bottom")
	)
	(footprint ""
		(layer "F.Cu")
		(at 75.705462 -39.675562)
		(property "Reference" "C2017"
			(at 0 0 0)
			(layer "F.SilkS")
			(hide yes)
			(effects
				(font
					(size 1.27 1.27)
				)
			)
		)
		(property "Value" ""
			(at 0 0 0)
			(layer "F.Fab")
			(effects
				(font
					(size 1.27 1.27)
				)
			)
		)
		(duplicate_pad_numbers_are_jumpers no)
		(fp_line
			(start -0.7874 -0.4064)
			(end 0.7874 -0.4064)
			(stroke
				(width 0.1524)
				(type default)
			)
			(layer "F.SilkS")
		)
		(fp_line
			(start -0.7874 0.4064)
			(end -0.7874 -0.4064)
			(stroke
				(width 0.1524)
				(type default)
			)
			(layer "F.SilkS")
		)
		(fp_line
			(start 0.7874 -0.4064)
			(end 0.7874 0.4064)
			(stroke
				(width 0.1524)
				(type default)
			)
			(layer "F.SilkS")
		)
		(fp_line
			(start 0.7874 0.4064)
			(end -0.7874 0.4064)
			(stroke
				(width 0.1524)
				(type default)
			)
			(layer "F.SilkS")
		)
		(fp_line
			(start -0.67945 -0.305054)
			(end -0.12065 -0.305054)
			(stroke
				(width 0.1)
				(type default)
			)
			(layer "F.Fab")
		)
		(fp_line
			(start -0.67945 0.3048)
			(end -0.67945 -0.305054)
			(stroke
				(width 0.1)
				(type default)
			)
			(layer "F.Fab")
		)
		(fp_line
			(start -0.12065 -0.305054)
			(end -0.12065 -0.2794)
			(stroke
				(width 0.1)
				(type default)
			)
			(layer "F.Fab")
		)
		(fp_line
			(start -0.12065 -0.2794)
			(end 0.12065 -0.2794)
			(stroke
				(width 0.1)
				(type default)
			)
			(layer "F.Fab")
		)
		(fp_line
			(start -0.12065 0.2794)
			(end -0.12065 0.3048)
			(stroke
				(width 0.1)
				(type default)
			)
			(layer "F.Fab")
		)
		(fp_line
			(start -0.12065 0.3048)
			(end -0.67945 0.3048)
			(stroke
				(width 0.1)
				(type default)
			)
			(layer "F.Fab")
		)
		(fp_line
			(start 0.120396 0.2794)
			(end -0.12065 0.2794)
			(stroke
				(width 0.1)
				(type default)
			)
			(layer "F.Fab")
		)
		(fp_line
			(start 0.120396 0.3048)
			(end 0.120396 0.2794)
			(stroke
				(width 0.1)
				(type default)
			)
			(layer "F.Fab")
		)
		(fp_line
			(start 0.12065 -0.3048)
			(end 0.67945 -0.3048)
			(stroke
				(width 0.1)
				(type default)
			)
			(layer "F.Fab")
		)
		(fp_line
			(start 0.12065 -0.2794)
			(end 0.12065 -0.3048)
			(stroke
				(width 0.1)
				(type default)
			)
			(layer "F.Fab")
		)
		(fp_line
			(start 0.67945 -0.3048)
			(end 0.67945 0.3048)
			(stroke
				(width 0.1)
				(type default)
			)
			(layer "F.Fab")
		)
		(fp_line
			(start 0.67945 0.3048)
			(end 0.120396 0.3048)
			(stroke
				(width 0.1)
				(type default)
			)
			(layer "F.Fab")
		)
		(pad "1" smd circle
			(at -0.40005 0)
			(size 0 0)
			(layers "F.Cu" "F.Mask" "F.Paste")
			(net "P3V3_OCP_V3_2_R")
		)
		(pad "2" smd circle
			(at 0.40005 0)
			(size 0 0)
			(layers "F.Cu" "F.Mask" "F.Paste")
			(net "GND")
		)
	)
	(footprint ""
		(layer "F.Cu")
		(at 403.951186 -61.94806)
		(property "Reference" "R777"
			(at 0 0 0)
			(layer "F.SilkS")
			(hide yes)
			(effects
				(font
					(size 1.27 1.27)
				)
			)
		)
		(property "Value" ""
			(at 0 0 0)
			(layer "F.Fab")
			(effects
				(font
					(size 1.27 1.27)
				)
			)
		)
		(duplicate_pad_numbers_are_jumpers no)
		(fp_line
			(start -0.7874 -0.4064)
			(end 0.7874 -0.4064)
			(stroke
				(width 0.1524)
				(type default)
			)
			(layer "F.SilkS")
		)
		(fp_line
			(start -0.7874 0.4064)
			(end -0.7874 -0.4064)
			(stroke
				(width 0.1524)
				(type default)
			)
			(layer "F.SilkS")
		)
		(fp_line
			(start 0.7874 -0.4064)
			(end 0.7874 0.4064)
			(stroke
				(width 0.1524)
				(type default)
			)
			(layer "F.SilkS")
		)
		(fp_line
			(start 0.7874 0.4064)
			(end -0.7874 0.4064)
			(stroke
				(width 0.1524)
				(type default)
			)
			(layer "F.SilkS")
		)
		(fp_line
			(start -0.67945 -0.305054)
			(end -0.12065 -0.305054)
			(stroke
				(width 0.1)
				(type default)
			)
			(layer "F.Fab")
		)
		(fp_line
			(start -0.67945 0.3048)
			(end -0.67945 -0.305054)
			(stroke
				(width 0.1)
				(type default)
			)
			(layer "F.Fab")
		)
		(fp_line
			(start -0.12065 -0.305054)
			(end -0.12065 -0.2794)
			(stroke
				(width 0.1)
				(type default)
			)
			(layer "F.Fab")
		)
		(fp_line
			(start -0.12065 -0.2794)
			(end 0.12065 -0.2794)
			(stroke
				(width 0.1)
				(type default)
			)
			(layer "F.Fab")
		)
		(fp_line
			(start -0.12065 0.2794)
			(end -0.12065 0.3048)
			(stroke
				(width 0.1)
				(type default)
			)
			(layer "F.Fab")
		)
		(fp_line
			(start -0.12065 0.3048)
			(end -0.67945 0.3048)
			(stroke
				(width 0.1)
				(type default)
			)
			(layer "F.Fab")
		)
		(fp_line
			(start 0.120396 0.2794)
			(end -0.12065 0.2794)
			(stroke
				(width 0.1)
				(type default)
			)
			(layer "F.Fab")
		)
		(fp_line
			(start 0.120396 0.3048)
			(end 0.120396 0.2794)
			(stroke
				(width 0.1)
				(type default)
			)
			(layer "F.Fab")
		)
		(fp_line
			(start 0.12065 -0.3048)
			(end 0.67945 -0.3048)
			(stroke
				(width 0.1)
				(type default)
			)
			(layer "F.Fab")
		)
		(fp_line
			(start 0.12065 -0.2794)
			(end 0.12065 -0.3048)
			(stroke
				(width 0.1)
				(type default)
			)
			(layer "F.Fab")
		)
		(fp_line
			(start 0.67945 -0.3048)
			(end 0.67945 0.3048)
			(stroke
				(width 0.1)
				(type default)
			)
			(layer "F.Fab")
		)
		(fp_line
			(start 0.67945 0.3048)
			(end 0.120396 0.3048)
			(stroke
				(width 0.1)
				(type default)
			)
			(layer "F.Fab")
		)
		(pad "1" smd circle
			(at -0.40005 0)
			(size 0 0)
			(layers "F.Cu" "F.Mask" "F.Paste")
			(net "JTAG_DBP_PREQ_N_R")
		)
		(pad "2" smd circle
			(at 0.40005 0)
			(size 0 0)
			(layers "F.Cu" "F.Mask" "F.Paste")
			(net "JTAG_DBP_PREQ_N")
		)
	)
)
